(kicad_pcb
	(version 20260206)
	(generator "pcbnew")
	(generator_version "10.0")
	(general
		(thickness 1.6)
		(legacy_teardrops no)
	)
	(paper "A4")
	(title_block
		(title "Wiwynn_Tioga_Pass_MB.brd")
		(comment 1 "Tioga Pass / footprints 3751-3758 of 4770")
	)
	(layers
		(0 "F.Cu" signal "TOP")
		(4 "In1.Cu" signal "L2GND")
		(6 "In2.Cu" signal "L3")
		(8 "In3.Cu" signal "L4GND")
		(10 "In4.Cu" signal "L5")
		(12 "In5.Cu" signal "L6GND")
		(14 "In6.Cu" signal "L7VCC")
		(16 "In7.Cu" signal "L8VCC")
		(18 "In8.Cu" signal "L9GND")
		(20 "In9.Cu" signal "L10")
		(22 "In10.Cu" signal "L11GND")
		(24 "In11.Cu" signal "L12")
		(26 "In12.Cu" signal "L13GND")
		(2 "B.Cu" signal "BOTTOM")
		(9 "F.Adhes" user "F.Adhesive")
		(11 "B.Adhes" user "B.Adhesive")
		(13 "F.Paste" user "Package Geometry/Pastemask Top")
		(15 "B.Paste" user "Package Geometry/Pastemask Bottom")
		(5 "F.SilkS" user "Ref Des/Silkscreen Top")
		(7 "B.SilkS" user "Ref Des/Silkscreen Bottom")
		(1 "F.Mask" user "Board Geometry/Soldermask Top")
		(3 "B.Mask" user "Board Geometry/Soldermask Bottom")
		(17 "Dwgs.User" user "User.Drawings")
		(19 "Cmts.User" user "User.Comments")
		(21 "Eco1.User" user "User.Eco1")
		(23 "Eco2.User" user "User.Eco2")
		(25 "Edge.Cuts" user "Board Geometry/Outline")
		(27 "Margin" user)
		(31 "F.CrtYd" user "Package Geometry/Place Bound Top")
		(29 "B.CrtYd" user "Package Geometry/Place Bound Bottom")
		(35 "F.Fab" user "Ref Des/Assembly Top")
		(33 "B.Fab" user "Ref Des/Assembly Bottom")
	)
	(footprint ""
		(layer "B.Cu")
		(at 440.4614 -52.2986)
		(property "Reference" "C2R10"
			(at 0 0 0)
			(layer "B.SilkS")
			(hide yes)
			(effects
				(font
					(size 1.27 1.27)
				)
				(justify mirror)
			)
		)
		(property "Value" ""
			(at 0 0 0)
			(layer "B.Fab")
			(effects
				(font
					(size 1.27 1.27)
				)
				(justify mirror)
			)
		)
		(duplicate_pad_numbers_are_jumpers no)
		(fp_poly
			(pts
				(xy -0.3048 -0.1016) (xy -0.3048 0.9906) (xy 0.3048 0.9906) (xy 0.3048 -0.1016)
			)
			(stroke
				(width 0)
				(type default)
			)
			(fill no)
			(layer "B.CrtYd")
		)
		(fp_line
			(start -0.3048 -0.1016)
			(end 0.3048 -0.1016)
			(stroke
				(width 0.1)
				(type default)
			)
			(layer "B.Fab")
		)
		(fp_line
			(start -0.3048 0.9906)
			(end -0.3048 -0.1016)
			(stroke
				(width 0.1)
				(type default)
			)
			(layer "B.Fab")
		)
		(fp_line
			(start 0.3048 -0.1016)
			(end 0.3048 0.9906)
			(stroke
				(width 0.1)
				(type default)
			)
			(layer "B.Fab")
		)
		(fp_line
			(start 0.3048 0.9906)
			(end -0.3048 0.9906)
			(stroke
				(width 0.1)
				(type default)
			)
			(layer "B.Fab")
		)
		(pad "1" smd rect
			(at 0 0 180)
			(size 0.508 0.508)
			(layers "B.Cu" "B.Mask" "B.Paste")
			(net "P3E_CPU0_PE3_OCP_TXP<7>")
		)
		(pad "2" smd rect
			(at 0 0.889 180)
			(size 0.508 0.508)
			(layers "B.Cu" "B.Mask" "B.Paste")
			(net "P3E_OCP_CPU0_PE3_C_TXP<7>")
		)
		(zone
			(layer "B.Cu")
			(hatch none 0.5)
			(connect_pads
				(clearance 0)
			)
			(min_thickness 0.25)
			(keepout
				(tracks allowed)
				(vias not_allowed)
				(pads allowed)
				(copperpour not_allowed)
				(footprints allowed)
			)
			(placement
				(enabled no)
				(sheetname "")
			)
			(fill
				(thermal_gap 0.5)
				(thermal_bridge_width 0.5)
				(island_removal_mode 0)
			)
			(polygon
				(pts
					(xy 440.7154 -52.0446) (xy 440.2074 -52.0446) (xy 440.2074 -51.6636) (xy 440.7154 -51.6636)
				)
			)
		)
		(zone
			(layer "B.Cu")
			(hatch none 0.5)
			(connect_pads
				(clearance 0)
			)
			(min_thickness 0.25)
			(keepout
				(tracks not_allowed)
				(vias allowed)
				(pads allowed)
				(copperpour not_allowed)
				(footprints allowed)
			)
			(placement
				(enabled no)
				(sheetname "")
			)
			(fill
				(thermal_gap 0.5)
				(thermal_bridge_width 0.5)
				(island_removal_mode 0)
			)
			(polygon
				(pts
					(xy 440.7154 -51.6636) (xy 440.2074 -51.6636) (xy 440.2074 -52.0446) (xy 440.7154 -52.0446)
				)
			)
		)
	)
	(footprint ""
		(layer "B.Cu")
		(at 269.902686 -79.60614 180)
		(property "Reference" "C5P13"
			(at 0 0 0)
			(layer "B.SilkS")
			(hide yes)
			(effects
				(font
					(size 1.27 1.27)
				)
				(justify mirror)
			)
		)
		(property "Value" ""
			(at 0 0 0)
			(layer "B.Fab")
			(effects
				(font
					(size 1.27 1.27)
				)
				(justify mirror)
			)
		)
		(duplicate_pad_numbers_are_jumpers no)
		(fp_poly
			(pts
				(xy 0.7239 -0.2159) (xy -0.7239 -0.2159) (xy -0.7239 1.9939) (xy 0.7239 1.9939)
			)
			(stroke
				(width 0)
				(type default)
			)
			(fill no)
			(layer "B.CrtYd")
		)
		(fp_line
			(start 0.7239 1.9939)
			(end -0.7239 1.9939)
			(stroke
				(width 0.1)
				(type default)
			)
			(layer "B.Fab")
		)
		(fp_line
			(start 0.7239 -0.2159)
			(end 0.7239 1.9939)
			(stroke
				(width 0.1)
				(type default)
			)
			(layer "B.Fab")
		)
		(fp_line
			(start -0.7239 1.9939)
			(end -0.7239 -0.2159)
			(stroke
				(width 0.1)
				(type default)
			)
			(layer "B.Fab")
		)
		(fp_line
			(start -0.7239 -0.2159)
			(end 0.7239 -0.2159)
			(stroke
				(width 0.1)
				(type default)
			)
			(layer "B.Fab")
		)
		(pad "1" smd rect
			(at 0 0)
			(size 1.27 1.016)
			(layers "B.Cu" "B.Mask" "B.Paste")
			(net "PVCCMCP_CPU0")
		)
		(pad "2" smd rect
			(at 0 1.778)
			(size 1.27 1.016)
			(layers "B.Cu" "B.Mask" "B.Paste")
			(net "GND")
		)
		(zone
			(layer "B.Cu")
			(hatch none 0.5)
			(connect_pads
				(clearance 0)
			)
			(min_thickness 0.25)
			(keepout
				(tracks not_allowed)
				(vias allowed)
				(pads allowed)
				(copperpour not_allowed)
				(footprints allowed)
			)
			(placement
				(enabled no)
				(sheetname "")
			)
			(fill
				(thermal_gap 0.5)
				(thermal_bridge_width 0.5)
				(island_removal_mode 0)
			)
			(polygon
				(pts
					(xy 269.267686 -80.11414) (xy 270.537686 -80.11414) (xy 270.537686 -80.87614) (xy 269.267686 -80.87614)
				)
			)
		)
	)
	(footprint ""
		(layer "B.Cu")
		(at 318.543432 -8.128 -90)
		(property "Reference" "C4U2"
			(at 0 0 90)
			(layer "B.SilkS")
			(hide yes)
			(effects
				(font
					(size 1.27 1.27)
				)
				(justify mirror)
			)
		)
		(property "Value" ""
			(at 0 0 90)
			(layer "B.Fab")
			(effects
				(font
					(size 1.27 1.27)
				)
				(justify mirror)
			)
		)
		(duplicate_pad_numbers_are_jumpers no)
		(fp_poly
			(pts
				(xy 0.4953 -0.2032) (xy -0.4953 -0.2032) (xy -0.4953 1.6002) (xy 0.4953 1.6002)
			)
			(stroke
				(width 0)
				(type default)
			)
			(fill no)
			(layer "B.CrtYd")
		)
		(fp_line
			(start -0.4953 1.6002)
			(end 0.4953 1.6002)
			(stroke
				(width 0.1)
				(type default)
			)
			(layer "B.Fab")
		)
		(fp_line
			(start 0.4953 1.6002)
			(end 0.4953 -0.2032)
			(stroke
				(width 0.1)
				(type default)
			)
			(layer "B.Fab")
		)
		(fp_line
			(start -0.4953 -0.2032)
			(end -0.4953 1.6002)
			(stroke
				(width 0.1)
				(type default)
			)
			(layer "B.Fab")
		)
		(fp_line
			(start 0.4953 -0.2032)
			(end -0.4953 -0.2032)
			(stroke
				(width 0.1)
				(type default)
			)
			(layer "B.Fab")
		)
		(pad "1" smd rect
			(at 0 0 90)
			(size 0.762 0.889)
			(layers "B.Cu" "B.Mask" "B.Paste")
			(net "PVPP_ABC")
		)
		(pad "2" smd rect
			(at 0 1.397 90)
			(size 0.762 0.889)
			(layers "B.Cu" "B.Mask" "B.Paste")
			(net "GND")
		)
		(zone
			(layer "B.Cu")
			(hatch none 0.5)
			(connect_pads
				(clearance 0)
			)
			(min_thickness 0.25)
			(keepout
				(tracks not_allowed)
				(vias allowed)
				(pads allowed)
				(copperpour not_allowed)
				(footprints allowed)
			)
			(placement
				(enabled no)
				(sheetname "")
			)
			(fill
				(thermal_gap 0.5)
				(thermal_bridge_width 0.5)
				(island_removal_mode 0)
			)
			(polygon
				(pts
					(xy 318.098932 -7.747) (xy 318.098932 -8.509) (xy 317.590932 -8.509) (xy 317.590932 -7.747)
				)
			)
		)
	)
	(footprint ""
		(layer "B.Cu")
		(at 416.470846 -44.650152 180)
		(property "Reference" "R9F23"
			(at 0 0 0)
			(layer "B.SilkS")
			(hide yes)
			(effects
				(font
					(size 1.27 1.27)
				)
				(justify mirror)
			)
		)
		(property "Value" ""
			(at 0 0 0)
			(layer "B.Fab")
			(effects
				(font
					(size 1.27 1.27)
				)
				(justify mirror)
			)
		)
		(duplicate_pad_numbers_are_jumpers no)
		(fp_poly
			(pts
				(xy 0.2794 -0.1016) (xy -0.2794 -0.1016) (xy -0.2794 0.9906) (xy 0.2794 0.9906)
			)
			(stroke
				(width 0)
				(type default)
			)
			(fill no)
			(layer "B.CrtYd")
		)
		(fp_line
			(start 0.2794 0.9906)
			(end -0.2794 0.9906)
			(stroke
				(width 0.1)
				(type default)
			)
			(layer "B.Fab")
		)
		(fp_line
			(start 0.2794 -0.1016)
			(end 0.2794 0.9906)
			(stroke
				(width 0.1)
				(type default)
			)
			(layer "B.Fab")
		)
		(fp_line
			(start -0.2794 0.9906)
			(end -0.2794 -0.1016)
			(stroke
				(width 0.1)
				(type default)
			)
			(layer "B.Fab")
		)
		(fp_line
			(start -0.2794 -0.1016)
			(end 0.2794 -0.1016)
			(stroke
				(width 0.1)
				(type default)
			)
			(layer "B.Fab")
		)
		(pad "1" smd rect
			(at 0 0)
			(size 0.508 0.508)
			(layers "B.Cu" "B.Mask" "B.Paste")
			(net "SMB_LAN_STBY_LVC3_SDA_R")
		)
		(pad "2" smd rect
			(at 0 0.889)
			(size 0.508 0.508)
			(layers "B.Cu" "B.Mask" "B.Paste")
			(net "SMB_LAN_STBY_LVC3_SDA")
		)
		(zone
			(layer "B.Cu")
			(hatch none 0.5)
			(connect_pads
				(clearance 0)
			)
			(min_thickness 0.25)
			(keepout
				(tracks not_allowed)
				(vias allowed)
				(pads allowed)
				(copperpour not_allowed)
				(footprints allowed)
			)
			(placement
				(enabled no)
				(sheetname "")
			)
			(fill
				(thermal_gap 0.5)
				(thermal_bridge_width 0.5)
				(island_removal_mode 0)
			)
			(polygon
				(pts
					(xy 416.216846 -45.285152) (xy 416.724846 -45.285152) (xy 416.724846 -44.904152) (xy 416.216846 -44.904152)
				)
			)
		)
		(zone
			(layer "B.Cu")
			(hatch none 0.5)
			(connect_pads
				(clearance 0)
			)
			(min_thickness 0.25)
			(keepout
				(tracks allowed)
				(vias not_allowed)
				(pads allowed)
				(copperpour not_allowed)
				(footprints allowed)
			)
			(placement
				(enabled no)
				(sheetname "")
			)
			(fill
				(thermal_gap 0.5)
				(thermal_bridge_width 0.5)
				(island_removal_mode 0)
			)
			(polygon
				(pts
					(xy 416.216846 -44.904152) (xy 416.724846 -44.904152) (xy 416.724846 -45.285152) (xy 416.216846 -45.285152)
				)
			)
		)
	)
	(footprint ""
		(layer "B.Cu")
		(at 245.7323 -3.3528 -90)
		(property "Reference" "C5G50"
			(at -1.14681 0.76708 0)
			(unlocked yes)
			(layer "B.SilkS")
			(effects
				(font
					(size 0.7874 0.5842)
					(thickness 0.1524)
				)
				(justify mirror)
			)
		)
		(property "Value" ""
			(at 0 0 90)
			(layer "B.Fab")
			(effects
				(font
					(size 1.27 1.27)
				)
				(justify mirror)
			)
		)
		(duplicate_pad_numbers_are_jumpers no)
		(fp_rect
			(start 0.4953 1.6002)
			(end -0.4953 -0.2032)
			(stroke
				(width 0)
				(type default)
			)
			(fill no)
			(layer "B.CrtYd")
		)
		(fp_line
			(start -0.4953 1.6002)
			(end 0.4953 1.6002)
			(stroke
				(width 0.1)
				(type default)
			)
			(layer "B.Fab")
		)
		(fp_line
			(start 0.4953 1.6002)
			(end 0.4953 -0.2032)
			(stroke
				(width 0.1)
				(type default)
			)
			(layer "B.Fab")
		)
		(fp_line
			(start -0.4953 -0.2032)
			(end -0.4953 1.6002)
			(stroke
				(width 0.1)
				(type default)
			)
			(layer "B.Fab")
		)
		(fp_line
			(start 0.4953 -0.2032)
			(end -0.4953 -0.2032)
			(stroke
				(width 0.1)
				(type default)
			)
			(layer "B.Fab")
		)
		(pad "1" smd rect
			(at 0 0 90)
			(size 0.762 0.889)
			(layers "B.Cu" "B.Mask" "B.Paste")
			(net "PVDDQ_ABC")
		)
		(pad "2" smd rect
			(at 0 1.397 90)
			(size 0.762 0.889)
			(layers "B.Cu" "B.Mask" "B.Paste")
			(net "GND")
		)
		(zone
			(layer "B.Cu")
			(hatch none 0.5)
			(connect_pads
				(clearance 0)
			)
			(min_thickness 0.25)
			(keepout
				(tracks not_allowed)
				(vias allowed)
				(pads allowed)
				(copperpour not_allowed)
				(footprints allowed)
			)
			(placement
				(enabled no)
				(sheetname "")
			)
			(fill
				(thermal_gap 0.5)
				(thermal_bridge_width 0.5)
				(island_removal_mode 0)
			)
			(polygon
				(pts
					(xy 244.7798 -2.9718) (xy 245.2878 -2.9718) (xy 245.2878 -3.7338) (xy 244.7798 -3.7338)
				)
			)
		)
	)
	(footprint ""
		(layer "B.Cu")
		(at 372.1354 -131.0894 -90)
		(property "Reference" "FB3M4"
			(at 0 0 90)
			(layer "B.SilkS")
			(hide yes)
			(effects
				(font
					(size 1.27 1.27)
				)
				(justify mirror)
			)
		)
		(property "Value" ""
			(at 0 0 90)
			(layer "B.Fab")
			(effects
				(font
					(size 1.27 1.27)
				)
				(justify mirror)
			)
		)
		(duplicate_pad_numbers_are_jumpers no)
		(fp_rect
			(start 0.15113 0.47498)
			(end -1.59893 -0.47498)
			(stroke
				(width 0)
				(type default)
			)
			(fill no)
			(layer "B.CrtYd")
		)
		(fp_line
			(start -1.59893 0.47498)
			(end 0.15113 0.47498)
			(stroke
				(width 0.1)
				(type default)
			)
			(layer "B.Fab")
		)
		(fp_line
			(start 0.15113 0.47498)
			(end 0.15113 -0.47498)
			(stroke
				(width 0.1)
				(type default)
			)
			(layer "B.Fab")
		)
		(fp_line
			(start -1.59893 -0.47498)
			(end -1.59893 0.47498)
			(stroke
				(width 0.1)
				(type default)
			)
			(layer "B.Fab")
		)
		(fp_line
			(start 0.15113 -0.47498)
			(end -1.59893 -0.47498)
			(stroke
				(width 0.1)
				(type default)
			)
			(layer "B.Fab")
		)
		(pad "1" smd rect
			(at 0 0 90)
			(size 0.9398 0.9398)
			(layers "B.Cu" "B.Mask" "B.Paste")
			(net "P1V05_PCH_STBY")
		)
		(pad "2" smd rect
			(at -1.4478 0 90)
			(size 0.9398 0.9398)
			(layers "B.Cu" "B.Mask" "B.Paste")
			(net "P1V05_PCH_STBY_ISCLK_PLL")
		)
		(zone
			(layer "B.Cu")
			(hatch none 0.5)
			(connect_pads
				(clearance 0)
			)
			(min_thickness 0.25)
			(keepout
				(tracks not_allowed)
				(vias allowed)
				(pads allowed)
				(copperpour not_allowed)
				(footprints allowed)
			)
			(placement
				(enabled no)
				(sheetname "")
			)
			(fill
				(thermal_gap 0.5)
				(thermal_bridge_width 0.5)
				(island_removal_mode 0)
			)
			(polygon
				(pts
					(xy 371.6655 -131.5593) (xy 372.6053 -131.5593) (xy 372.6053 -132.0673) (xy 371.6655 -132.0673)
				)
			)
		)
		(zone
			(layer "B.Cu")
			(hatch none 0.5)
			(connect_pads
				(clearance 0)
			)
			(min_thickness 0.25)
			(keepout
				(tracks allowed)
				(vias not_allowed)
				(pads allowed)
				(copperpour not_allowed)
				(footprints allowed)
			)
			(placement
				(enabled no)
				(sheetname "")
			)
			(fill
				(thermal_gap 0.5)
				(thermal_bridge_width 0.5)
				(island_removal_mode 0)
			)
			(polygon
				(pts
					(xy 371.6655 -131.5593) (xy 372.6053 -131.5593) (xy 372.6053 -132.0673) (xy 371.6655 -132.0673)
				)
			)
		)
	)
	(footprint ""
		(layer "B.Cu")
		(at 33.620456 -53.157882 90)
		(property "Reference" "C1E6"
			(at 0 0 90)
			(layer "B.SilkS")
			(hide yes)
			(effects
				(font
					(size 1.27 1.27)
				)
				(justify mirror)
			)
		)
		(property "Value" "*"
			(at -1.1811 -2.8194 90)
			(unlocked yes)
			(layer "B.Fab")
			(hide yes)
			(effects
				(font
					(size 1.27 1.016)
					(thickness 0.1524)
				)
				(justify mirror)
			)
		)
		(property "Device Type" "SC1U10V2KX-4-GP_SMD-BCG6-SC1U1A"
			(at -1.1811 -4.3434 90)
			(unlocked yes)
			(layer "B.Fab")
			(hide yes)
			(effects
				(font
					(size 1.27 1.016)
					(thickness 0.1524)
				)
				(justify mirror)
			)
		)
		(duplicate_pad_numbers_are_jumpers no)
		(fp_rect
			(start 0.4318 0.9525)
			(end -0.4318 -0.9525)
			(stroke
				(width 0)
				(type default)
			)
			(fill no)
			(layer "B.CrtYd")
		)
		(fp_rect
			(start 0.4318 0.9525)
			(end -0.4318 -0.9525)
			(stroke
				(width 0)
				(type default)
			)
			(fill no)
			(layer "B.Fab")
		)
		(pad "1" smd custom
			(at 0 -0.4445 270)
			(size 0.1524 0.1524)
			(layers "B.Cu" "B.Mask" "B.Paste")
			(net "P5V_STBY")
			(options
				(clearance outline)
				(anchor circle)
			)
			(primitives
				(gr_poly
					(pts
						(arc
							(start 0.3048 0.2032)
							(mid 0.275042 0.275042)
							(end 0.2032 0.3048)
						)
						(arc
							(start -0.2032 0.3048)
							(mid -0.275042 0.275042)
							(end -0.3048 0.2032)
						)
						(arc
							(start -0.3048 -0.2032)
							(mid -0.275042 -0.275042)
							(end -0.2032 -0.3048)
						)
						(arc
							(start 0.2032 -0.3048)
							(mid 0.275042 -0.275042)
							(end 0.3048 -0.2032)
						)
					)
					(width 0)
					(fill yes)
				)
			)
		)
		(pad "2" smd custom
			(at 0 0.4445 270)
			(size 0.1524 0.1524)
			(layers "B.Cu" "B.Mask" "B.Paste")
			(net "GND")
			(options
				(clearance outline)
				(anchor circle)
			)
			(primitives
				(gr_poly
					(pts
						(arc
							(start 0.3048 0.2032)
							(mid 0.275042 0.275042)
							(end 0.2032 0.3048)
						)
						(arc
							(start -0.2032 0.3048)
							(mid -0.275042 0.275042)
							(end -0.3048 0.2032)
						)
						(arc
							(start -0.3048 -0.2032)
							(mid -0.275042 -0.275042)
							(end -0.2032 -0.3048)
						)
						(arc
							(start 0.2032 -0.3048)
							(mid 0.275042 -0.275042)
							(end 0.3048 -0.2032)
						)
					)
					(width 0)
					(fill yes)
				)
			)
		)
	)
	(footprint ""
		(layer "B.Cu")
		(at 101.3968 -145.0086 90)
		(property "Reference" "C8L6"
			(at -1.848866 0.752348 90)
			(unlocked yes)
			(layer "B.SilkS")
			(effects
				(font
					(size 1.27 0.9652)
					(thickness 0.1524)
				)
				(justify mirror)
			)
		)
		(property "Value" ""
			(at 0 0 90)
			(layer "B.Fab")
			(effects
				(font
					(size 1.27 1.27)
				)
				(justify mirror)
			)
		)
		(duplicate_pad_numbers_are_jumpers no)
		(fp_rect
			(start 0.500126 1.598422)
			(end -0.500126 -0.201422)
			(stroke
				(width 0)
				(type default)
			)
			(fill no)
			(layer "B.CrtYd")
		)
		(fp_line
			(start 0.500126 -0.201422)
			(end -0.500126 -0.201422)
			(stroke
				(width 0.1)
				(type default)
			)
			(layer "B.Fab")
		)
		(fp_line
			(start -0.500126 -0.201422)
			(end -0.500126 1.598422)
			(stroke
				(width 0.1)
				(type default)
			)
			(layer "B.Fab")
		)
		(fp_line
			(start 0.500126 1.598422)
			(end 0.500126 -0.201422)
			(stroke
				(width 0.1)
				(type default)
			)
			(layer "B.Fab")
		)
		(fp_line
			(start -0.500126 1.598422)
			(end 0.500126 1.598422)
			(stroke
				(width 0.1)
				(type default)
			)
			(layer "B.Fab")
		)
		(pad "1" smd rect
			(at 0 0)
			(size 0.889 0.9906)
			(layers "B.Cu" "B.Mask" "B.Paste")
			(net "PVDDQ_KLM")
		)
		(pad "2" smd rect
			(at 0 1.397)
			(size 0.889 0.9906)
			(layers "B.Cu" "B.Mask" "B.Paste")
			(net "GND")
		)
		(zone
			(layer "B.Cu")
			(hatch none 0.5)
			(connect_pads
				(clearance 0)
			)
			(min_thickness 0.25)
			(keepout
				(tracks not_allowed)
				(vias allowed)
				(pads allowed)
				(copperpour not_allowed)
				(footprints allowed)
			)
			(placement
				(enabled no)
				(sheetname "")
			)
			(fill
				(thermal_gap 0.5)
				(thermal_bridge_width 0.5)
				(island_removal_mode 0)
			)
			(polygon
				(pts
					(xy 102.3493 -145.5039) (xy 101.8413 -145.5039) (xy 101.8413 -144.5133) (xy 102.3493 -144.5133)
				)
			)
		)
		(zone
			(layer "B.Cu")
			(hatch none 0.5)
			(connect_pads
				(clearance 0)
			)
			(min_thickness 0.25)
			(keepout
				(tracks allowed)
				(vias not_allowed)
				(pads allowed)
				(copperpour not_allowed)
				(footprints allowed)
			)
			(placement
				(enabled no)
				(sheetname "")
			)
			(fill
				(thermal_gap 0.5)
				(thermal_bridge_width 0.5)
				(island_removal_mode 0)
			)
			(polygon
				(pts
					(xy 102.3493 -145.5039) (xy 101.8413 -145.5039) (xy 101.8413 -144.5133) (xy 102.3493 -144.5133)
				)
			)
		)
	)
)
